# S9S_MB_2U (Grand Teton) — schematic netlist excerpt (pin names and nets, part order shuffled) for the footprints in the layout excerpt that follows; sources: Cadence DE-HDL packaged netlist, KiCad conversion of 03242023_DA0F0TMBIJ0_F0T_Motherboard_J_brd_V01_OCP.brd

C616  Q_CAP  1UF 25V 10% EMPTY  pkg C0402  page 130 : A = RST_PLD_CPU1_DRAM_EF_N ; B = GND
R1897  Q_RES  100 1% CHIP  pkg 0402LF  page 154 : A = OCP_SFF_ISO_BIF1_EN ; B = GND
PC382  Q_CAP  22UF 4V 20% X6S  pkg C0805  page 297 : A = PVCCD_HV_CPU1 ; B = GND

(kicad_pcb
	(version 20260206)
	(generator "pcbnew")
	(generator_version "10.0")
	(general
		(thickness 1.6)
		(legacy_teardrops no)
	)
	(paper "A4")
	(title_block
		(title "03242023_DA0F0TMBIJ0_F0T_Motherboard_J_brd_V01_OCP.brd")
		(comment 1 "Grand Teton / footprints 5851-5853 of 6105")
	)
	(layers
		(0 "F.Cu" signal "TOP")
		(4 "In1.Cu" signal "GND")
		(6 "In2.Cu" signal "IN1")
		(8 "In3.Cu" signal "GND1")
		(10 "In4.Cu" signal "IN2")
		(12 "In5.Cu" signal "GND2")
		(14 "In6.Cu" signal "IN3")
		(16 "In7.Cu" signal "GND3")
		(18 "In8.Cu" signal "VCC")
		(20 "In9.Cu" signal "VCC1")
		(22 "In10.Cu" signal "GND4")
		(24 "In11.Cu" signal "IN4")
		(26 "In12.Cu" signal "GND5")
		(28 "In13.Cu" signal "IN5")
		(30 "In14.Cu" signal "GND6")
		(32 "In15.Cu" signal "IN6")
		(34 "In16.Cu" signal "GND7")
		(2 "B.Cu" signal "BOTTOM")
		(9 "F.Adhes" user "F.Adhesive")
		(11 "B.Adhes" user "B.Adhesive")
		(13 "F.Paste" user "Package Geometry/Pastemask Top")
		(15 "B.Paste" user "Package Geometry/Pastemask Bottom")
		(5 "F.SilkS" user "Ref Des/Silkscreen Top")
		(7 "B.SilkS" user "Ref Des/Silkscreen Bottom")
		(1 "F.Mask" user "Board Geometry/Soldermask Top")
		(3 "B.Mask" user "Board Geometry/Soldermask Bottom")
		(17 "Dwgs.User" user "User.Drawings")
		(19 "Cmts.User" user "User.Comments")
		(21 "Eco1.User" user "User.Eco1")
		(23 "Eco2.User" user "User.Eco2")
		(25 "Edge.Cuts" user "Board Geometry/Outline")
		(27 "Margin" user)
		(31 "F.CrtYd" user "Package Geometry/Place Bound Top")
		(29 "B.CrtYd" user "Package Geometry/Place Bound Bottom")
		(35 "F.Fab" user "Ref Des/Assembly Top")
		(33 "B.Fab" user "Ref Des/Assembly Bottom")
	)
	(footprint ""
		(layer "B.Cu")
		(at 433.832 -24.094948 -90)
		(property "Reference" "R1897"
			(at 0 0 90)
			(layer "B.SilkS")
			(hide yes)
			(effects
				(font
					(size 1.27 1.27)
				)
				(justify mirror)
			)
		)
		(property "Value" ""
			(at 0 0 90)
			(layer "B.Fab")
			(effects
				(font
					(size 1.27 1.27)
				)
				(justify mirror)
			)
		)
		(duplicate_pad_numbers_are_jumpers no)
		(fp_line
			(start -0.7874 0.4064)
			(end 0.7874 0.4064)
			(stroke
				(width 0.1524)
				(type default)
			)
			(layer "B.SilkS")
		)
		(fp_line
			(start 0.7874 0.4064)
			(end 0.7874 -0.4064)
			(stroke
				(width 0.1524)
				(type default)
			)
			(layer "B.SilkS")
		)
		(fp_line
			(start -0.7874 -0.4064)
			(end -0.7874 0.4064)
			(stroke
				(width 0.1524)
				(type default)
			)
			(layer "B.SilkS")
		)
		(fp_line
			(start 0.7874 -0.4064)
			(end -0.7874 -0.4064)
			(stroke
				(width 0.1524)
				(type default)
			)
			(layer "B.SilkS")
		)
		(fp_line
			(start -0.67945 0.3048)
			(end -0.120396 0.3048)
			(stroke
				(width 0.1)
				(type default)
			)
			(layer "B.Fab")
		)
		(fp_line
			(start -0.120396 0.3048)
			(end -0.120396 0.2794)
			(stroke
				(width 0.1)
				(type default)
			)
			(layer "B.Fab")
		)
		(fp_line
			(start 0.12065 0.3048)
			(end 0.67945 0.3048)
			(stroke
				(width 0.1)
				(type default)
			)
			(layer "B.Fab")
		)
		(fp_line
			(start 0.67945 0.3048)
			(end 0.67945 -0.305054)
			(stroke
				(width 0.1)
				(type default)
			)
			(layer "B.Fab")
		)
		(fp_line
			(start -0.120396 0.2794)
			(end 0.12065 0.2794)
			(stroke
				(width 0.1)
				(type default)
			)
			(layer "B.Fab")
		)
		(fp_line
			(start 0.12065 0.2794)
			(end 0.12065 0.3048)
			(stroke
				(width 0.1)
				(type default)
			)
			(layer "B.Fab")
		)
		(fp_line
			(start -0.12065 -0.2794)
			(end -0.12065 -0.3048)
			(stroke
				(width 0.1)
				(type default)
			)
			(layer "B.Fab")
		)
		(fp_line
			(start 0.12065 -0.2794)
			(end -0.12065 -0.2794)
			(stroke
				(width 0.1)
				(type default)
			)
			(layer "B.Fab")
		)
		(fp_line
			(start -0.67945 -0.3048)
			(end -0.67945 0.3048)
			(stroke
				(width 0.1)
				(type default)
			)
			(layer "B.Fab")
		)
		(fp_line
			(start -0.12065 -0.3048)
			(end -0.67945 -0.3048)
			(stroke
				(width 0.1)
				(type default)
			)
			(layer "B.Fab")
		)
		(fp_line
			(start 0.12065 -0.305054)
			(end 0.12065 -0.2794)
			(stroke
				(width 0.1)
				(type default)
			)
			(layer "B.Fab")
		)
		(fp_line
			(start 0.67945 -0.305054)
			(end 0.12065 -0.305054)
			(stroke
				(width 0.1)
				(type default)
			)
			(layer "B.Fab")
		)
		(pad "1" smd circle
			(at 0.40005 0 90)
			(size 0 0)
			(layers "B.Cu" "B.Mask" "B.Paste")
			(net "OCP_SFF_ISO_BIF1_EN")
		)
		(pad "2" smd circle
			(at -0.40005 0 90)
			(size 0 0)
			(layers "B.Cu" "B.Mask" "B.Paste")
			(net "GND")
		)
	)
	(footprint ""
		(layer "B.Cu")
		(at 62.666372 -168.58488)
		(property "Reference" "PC382"
			(at 0 0 0)
			(layer "B.SilkS")
			(hide yes)
			(effects
				(font
					(size 1.27 1.27)
				)
				(justify mirror)
			)
		)
		(property "Value" ""
			(at 0 0 0)
			(layer "B.Fab")
			(effects
				(font
					(size 1.27 1.27)
				)
				(justify mirror)
			)
		)
		(duplicate_pad_numbers_are_jumpers no)
		(fp_line
			(start -1.524 -0.762)
			(end -1.524 0.762)
			(stroke
				(width 0.1524)
				(type default)
			)
			(layer "B.SilkS")
		)
		(fp_line
			(start -1.524 0.762)
			(end 1.524 0.762)
			(stroke
				(width 0.1524)
				(type default)
			)
			(layer "B.SilkS")
		)
		(fp_line
			(start 1.524 -0.762)
			(end -1.524 -0.762)
			(stroke
				(width 0.1524)
				(type default)
			)
			(layer "B.SilkS")
		)
		(fp_line
			(start 1.524 0.762)
			(end 1.524 -0.762)
			(stroke
				(width 0.1524)
				(type default)
			)
			(layer "B.SilkS")
		)
		(fp_line
			(start -1.1049 -0.724916)
			(end 1.1049 -0.724916)
			(stroke
				(width 0.1)
				(type default)
			)
			(layer "B.Fab")
		)
		(fp_line
			(start -1.1049 0.724916)
			(end -1.1049 -0.724916)
			(stroke
				(width 0.1)
				(type default)
			)
			(layer "B.Fab")
		)
		(fp_line
			(start 1.1049 -0.724916)
			(end 1.1049 0.724916)
			(stroke
				(width 0.1)
				(type default)
			)
			(layer "B.Fab")
		)
		(fp_line
			(start 1.1049 0.724916)
			(end -1.1049 0.724916)
			(stroke
				(width 0.1)
				(type default)
			)
			(layer "B.Fab")
		)
		(pad "1" smd rect
			(at 0.889 0)
			(size 1.016 1.27)
			(layers "B.Cu" "B.Mask" "B.Paste")
			(net "PVCCD_HV_CPU1")
		)
		(pad "2" smd rect
			(at -0.889 0)
			(size 1.016 1.27)
			(layers "B.Cu" "B.Mask" "B.Paste")
			(net "GND")
		)
	)
	(footprint ""
		(layer "B.Cu")
		(at 187.174886 -193.599816 -90)
		(property "Reference" "C616"
			(at 0 0 90)
			(layer "B.SilkS")
			(hide yes)
			(effects
				(font
					(size 1.27 1.27)
				)
				(justify mirror)
			)
		)
		(property "Value" ""
			(at 0 0 90)
			(layer "B.Fab")
			(effects
				(font
					(size 1.27 1.27)
				)
				(justify mirror)
			)
		)
		(duplicate_pad_numbers_are_jumpers no)
		(fp_line
			(start -0.7874 0.4064)
			(end 0.7874 0.4064)
			(stroke
				(width 0.1524)
				(type default)
			)
			(layer "B.SilkS")
		)
		(fp_line
			(start 0.7874 0.4064)
			(end 0.7874 -0.4064)
			(stroke
				(width 0.1524)
				(type default)
			)
			(layer "B.SilkS")
		)
		(fp_line
			(start -0.7874 -0.4064)
			(end -0.7874 0.4064)
			(stroke
				(width 0.1524)
				(type default)
			)
			(layer "B.SilkS")
		)
		(fp_line
			(start 0.7874 -0.4064)
			(end -0.7874 -0.4064)
			(stroke
				(width 0.1524)
				(type default)
			)
			(layer "B.SilkS")
		)
		(fp_line
			(start -0.67945 0.3048)
			(end -0.120396 0.3048)
			(stroke
				(width 0.1)
				(type default)
			)
			(layer "B.Fab")
		)
		(fp_line
			(start -0.120396 0.3048)
			(end -0.120396 0.2794)
			(stroke
				(width 0.1)
				(type default)
			)
			(layer "B.Fab")
		)
		(fp_line
			(start 0.12065 0.3048)
			(end 0.67945 0.3048)
			(stroke
				(width 0.1)
				(type default)
			)
			(layer "B.Fab")
		)
		(fp_line
			(start 0.67945 0.3048)
			(end 0.67945 -0.305054)
			(stroke
				(width 0.1)
				(type default)
			)
			(layer "B.Fab")
		)
		(fp_line
			(start -0.120396 0.2794)
			(end 0.12065 0.2794)
			(stroke
				(width 0.1)
				(type default)
			)
			(layer "B.Fab")
		)
		(fp_line
			(start 0.12065 0.2794)
			(end 0.12065 0.3048)
			(stroke
				(width 0.1)
				(type default)
			)
			(layer "B.Fab")
		)
		(fp_line
			(start -0.12065 -0.2794)
			(end -0.12065 -0.3048)
			(stroke
				(width 0.1)
				(type default)
			)
			(layer "B.Fab")
		)
		(fp_line
			(start 0.12065 -0.2794)
			(end -0.12065 -0.2794)
			(stroke
				(width 0.1)
				(type default)
			)
			(layer "B.Fab")
		)
		(fp_line
			(start -0.67945 -0.3048)
			(end -0.67945 0.3048)
			(stroke
				(width 0.1)
				(type default)
			)
			(layer "B.Fab")
		)
		(fp_line
			(start -0.12065 -0.3048)
			(end -0.67945 -0.3048)
			(stroke
				(width 0.1)
				(type default)
			)
			(layer "B.Fab")
		)
		(fp_line
			(start 0.12065 -0.305054)
			(end 0.12065 -0.2794)
			(stroke
				(width 0.1)
				(type default)
			)
			(layer "B.Fab")
		)
		(fp_line
			(start 0.67945 -0.305054)
			(end 0.12065 -0.305054)
			(stroke
				(width 0.1)
				(type default)
			)
			(layer "B.Fab")
		)
		(pad "1" smd circle
			(at 0.40005 0 90)
			(size 0 0)
			(layers "B.Cu" "B.Mask" "B.Paste")
			(net "RST_PLD_CPU1_DRAM_EF_N")
		)
		(pad "2" smd circle
			(at -0.40005 0 90)
			(size 0 0)
			(layers "B.Cu" "B.Mask" "B.Paste")
			(net "GND")
		)
	)
)
